FILE_TYPE=LIBRARY_PARTS;
primitive 'BZA462A';
  pin
    '2':
      PIN_NUMBER='(2)';
      BIDIRECTIONAL='TRUE';
      INPUT_LOAD='(-0.01,0.01)';
      OUTPUT_LOAD='(1.0,-1.0)';
    '5':
      PIN_NUMBER='(5)';
      BIDIRECTIONAL='TRUE';
      INPUT_LOAD='(-0.01,0.01)';
      OUTPUT_LOAD='(1.0,-1.0)';
    '1':
      PIN_NUMBER='(1)';
      BIDIRECTIONAL='TRUE';
      INPUT_LOAD='(-0.01,0.01)';
      OUTPUT_LOAD='(1.0,-1.0)';
    '3':
      PIN_NUMBER='(3)';
      BIDIRECTIONAL='TRUE';
      INPUT_LOAD='(-0.01,0.01)';
      OUTPUT_LOAD='(1.0,-1.0)';
    '4':
      PIN_NUMBER='(4)';
      BIDIRECTIONAL='TRUE';
      INPUT_LOAD='(-0.01,0.01)';
      OUTPUT_LOAD='(1.0,-1.0)';
    '6':
      PIN_NUMBER='(6)';
      BIDIRECTIONAL='TRUE';
      INPUT_LOAD='(-0.01,0.01)';
      OUTPUT_LOAD='(1.0,-1.0)';
  end_pin;
  body
    PART_NAME='BZA462A';
    BODY_NAME='BZA462A';
    PHYS_DES_PREFIX='D';
    CLASS='DISCRETE';
  end_body;
end_primitive;

END.
